# T6G (Grand Teton) — schematic netlist excerpt (pin names and nets, part order shuffled) for the footprints in the layout excerpt that follows; sources: Cadence DE-HDL packaged netlist, KiCad conversion of 04192023_DAF0TMB3IC0_F0TG_MB_C_brd_V02_OCP.brd

R3723  Q_RES  2.2K 5% CHIP  pkg 0402LF  page 252 : A = P3V3_AUX ; B = SMB_VR_3V3AUX_SCL
C6590  Q_CAP_DIFFBUS  DIFF BUS_0.22UF 6.3V 20% X6S  pkg C0201  page 297 : \1\ = P5E_CPU0_P2_TX_BUF_C_DN<12> ; \2\ = P5E_CPU0_P2_TX_BUF_DN<12>
R3451  Q_RES  4.7K 5% EMPTY  pkg 0402LF  page 128 : A = P3V3_AUX ; B = GPU_BASE_STBY_EN

(kicad_pcb
	(version 20260206)
	(generator "pcbnew")
	(generator_version "10.0")
	(general
		(thickness 1.6)
		(legacy_teardrops no)
	)
	(paper "A4")
	(title_block
		(title "04192023_DAF0TMB3IC0_F0TG_MB_C_brd_V02_OCP.brd")
		(comment 1 "Grand Teton / footprints 3523-3525 of 8354")
	)
	(layers
		(0 "F.Cu" signal "TOP")
		(4 "In1.Cu" signal "GND")
		(6 "In2.Cu" signal "IN1")
		(8 "In3.Cu" signal "GND1")
		(10 "In4.Cu" signal "IN2")
		(12 "In5.Cu" signal "GND2")
		(14 "In6.Cu" signal "IN3")
		(16 "In7.Cu" signal "GND3")
		(18 "In8.Cu" signal "VCC")
		(20 "In9.Cu" signal "VCC1")
		(22 "In10.Cu" signal "GND4")
		(24 "In11.Cu" signal "IN4")
		(26 "In12.Cu" signal "GND5")
		(28 "In13.Cu" signal "IN5")
		(30 "In14.Cu" signal "GND6")
		(32 "In15.Cu" signal "IN6")
		(34 "In16.Cu" signal "GND7")
		(2 "B.Cu" signal "BOTTOM")
		(9 "F.Adhes" user "F.Adhesive")
		(11 "B.Adhes" user "B.Adhesive")
		(13 "F.Paste" user "Package Geometry/Pastemask Top")
		(15 "B.Paste" user "Package Geometry/Pastemask Bottom")
		(5 "F.SilkS" user "Ref Des/Silkscreen Top")
		(7 "B.SilkS" user "Ref Des/Silkscreen Bottom")
		(1 "F.Mask" user "Board Geometry/Soldermask Top")
		(3 "B.Mask" user "Board Geometry/Soldermask Bottom")
		(17 "Dwgs.User" user "User.Drawings")
		(19 "Cmts.User" user "User.Comments")
		(21 "Eco1.User" user "User.Eco1")
		(23 "Eco2.User" user "User.Eco2")
		(25 "Edge.Cuts" user "Board Geometry/Outline")
		(27 "Margin" user)
		(31 "F.CrtYd" user "Package Geometry/Place Bound Top")
		(29 "B.CrtYd" user "Package Geometry/Place Bound Bottom")
		(35 "F.Fab" user "Ref Des/Assembly Top")
		(33 "B.Fab" user "Ref Des/Assembly Bottom")
	)
	(footprint ""
		(layer "F.Cu")
		(at 254.592836 -121.71045)
		(property "Reference" "R3723"
			(at 0 0 0)
			(layer "F.SilkS")
			(hide yes)
			(effects
				(font
					(size 1.27 1.27)
				)
			)
		)
		(property "Value" ""
			(at 0 0 0)
			(layer "F.Fab")
			(effects
				(font
					(size 1.27 1.27)
				)
			)
		)
		(duplicate_pad_numbers_are_jumpers no)
		(fp_line
			(start -0.7874 -0.4064)
			(end 0.7874 -0.4064)
			(stroke
				(width 0.1524)
				(type default)
			)
			(layer "F.SilkS")
		)
		(fp_line
			(start -0.7874 0.4064)
			(end -0.7874 -0.4064)
			(stroke
				(width 0.1524)
				(type default)
			)
			(layer "F.SilkS")
		)
		(fp_line
			(start 0.7874 -0.4064)
			(end 0.7874 0.4064)
			(stroke
				(width 0.1524)
				(type default)
			)
			(layer "F.SilkS")
		)
		(fp_line
			(start 0.7874 0.4064)
			(end -0.7874 0.4064)
			(stroke
				(width 0.1524)
				(type default)
			)
			(layer "F.SilkS")
		)
		(fp_line
			(start -0.67945 -0.305054)
			(end -0.12065 -0.305054)
			(stroke
				(width 0.1)
				(type default)
			)
			(layer "F.Fab")
		)
		(fp_line
			(start -0.67945 0.3048)
			(end -0.67945 -0.305054)
			(stroke
				(width 0.1)
				(type default)
			)
			(layer "F.Fab")
		)
		(fp_line
			(start -0.12065 -0.305054)
			(end -0.12065 -0.2794)
			(stroke
				(width 0.1)
				(type default)
			)
			(layer "F.Fab")
		)
		(fp_line
			(start -0.12065 -0.2794)
			(end 0.12065 -0.2794)
			(stroke
				(width 0.1)
				(type default)
			)
			(layer "F.Fab")
		)
		(fp_line
			(start -0.12065 0.2794)
			(end -0.12065 0.3048)
			(stroke
				(width 0.1)
				(type default)
			)
			(layer "F.Fab")
		)
		(fp_line
			(start -0.12065 0.3048)
			(end -0.67945 0.3048)
			(stroke
				(width 0.1)
				(type default)
			)
			(layer "F.Fab")
		)
		(fp_line
			(start 0.120396 0.2794)
			(end -0.12065 0.2794)
			(stroke
				(width 0.1)
				(type default)
			)
			(layer "F.Fab")
		)
		(fp_line
			(start 0.120396 0.3048)
			(end 0.120396 0.2794)
			(stroke
				(width 0.1)
				(type default)
			)
			(layer "F.Fab")
		)
		(fp_line
			(start 0.12065 -0.3048)
			(end 0.67945 -0.3048)
			(stroke
				(width 0.1)
				(type default)
			)
			(layer "F.Fab")
		)
		(fp_line
			(start 0.12065 -0.2794)
			(end 0.12065 -0.3048)
			(stroke
				(width 0.1)
				(type default)
			)
			(layer "F.Fab")
		)
		(fp_line
			(start 0.67945 -0.3048)
			(end 0.67945 0.3048)
			(stroke
				(width 0.1)
				(type default)
			)
			(layer "F.Fab")
		)
		(fp_line
			(start 0.67945 0.3048)
			(end 0.120396 0.3048)
			(stroke
				(width 0.1)
				(type default)
			)
			(layer "F.Fab")
		)
		(pad "1" smd circle
			(at -0.40005 0)
			(size 0 0)
			(layers "F.Cu" "F.Mask" "F.Paste")
			(net "P3V3_AUX")
		)
		(pad "2" smd circle
			(at 0.40005 0)
			(size 0 0)
			(layers "F.Cu" "F.Mask" "F.Paste")
			(net "SMB_VR_3V3AUX_SCL")
		)
	)
	(footprint ""
		(layer "F.Cu")
		(at 118.618 -431.038)
		(property "Reference" "R3451"
			(at 0 0 0)
			(layer "F.SilkS")
			(hide yes)
			(effects
				(font
					(size 1.27 1.27)
				)
			)
		)
		(property "Value" ""
			(at 0 0 0)
			(layer "F.Fab")
			(effects
				(font
					(size 1.27 1.27)
				)
			)
		)
		(duplicate_pad_numbers_are_jumpers no)
		(fp_line
			(start -0.7874 -0.4064)
			(end 0.7874 -0.4064)
			(stroke
				(width 0.1524)
				(type default)
			)
			(layer "F.SilkS")
		)
		(fp_line
			(start -0.7874 0.4064)
			(end -0.7874 -0.4064)
			(stroke
				(width 0.1524)
				(type default)
			)
			(layer "F.SilkS")
		)
		(fp_line
			(start 0.7874 -0.4064)
			(end 0.7874 0.4064)
			(stroke
				(width 0.1524)
				(type default)
			)
			(layer "F.SilkS")
		)
		(fp_line
			(start 0.7874 0.4064)
			(end -0.7874 0.4064)
			(stroke
				(width 0.1524)
				(type default)
			)
			(layer "F.SilkS")
		)
		(fp_line
			(start -0.67945 -0.305054)
			(end -0.12065 -0.305054)
			(stroke
				(width 0.1)
				(type default)
			)
			(layer "F.Fab")
		)
		(fp_line
			(start -0.67945 0.3048)
			(end -0.67945 -0.305054)
			(stroke
				(width 0.1)
				(type default)
			)
			(layer "F.Fab")
		)
		(fp_line
			(start -0.12065 -0.305054)
			(end -0.12065 -0.2794)
			(stroke
				(width 0.1)
				(type default)
			)
			(layer "F.Fab")
		)
		(fp_line
			(start -0.12065 -0.2794)
			(end 0.12065 -0.2794)
			(stroke
				(width 0.1)
				(type default)
			)
			(layer "F.Fab")
		)
		(fp_line
			(start -0.12065 0.2794)
			(end -0.12065 0.3048)
			(stroke
				(width 0.1)
				(type default)
			)
			(layer "F.Fab")
		)
		(fp_line
			(start -0.12065 0.3048)
			(end -0.67945 0.3048)
			(stroke
				(width 0.1)
				(type default)
			)
			(layer "F.Fab")
		)
		(fp_line
			(start 0.120396 0.2794)
			(end -0.12065 0.2794)
			(stroke
				(width 0.1)
				(type default)
			)
			(layer "F.Fab")
		)
		(fp_line
			(start 0.120396 0.3048)
			(end 0.120396 0.2794)
			(stroke
				(width 0.1)
				(type default)
			)
			(layer "F.Fab")
		)
		(fp_line
			(start 0.12065 -0.3048)
			(end 0.67945 -0.3048)
			(stroke
				(width 0.1)
				(type default)
			)
			(layer "F.Fab")
		)
		(fp_line
			(start 0.12065 -0.2794)
			(end 0.12065 -0.3048)
			(stroke
				(width 0.1)
				(type default)
			)
			(layer "F.Fab")
		)
		(fp_line
			(start 0.67945 -0.3048)
			(end 0.67945 0.3048)
			(stroke
				(width 0.1)
				(type default)
			)
			(layer "F.Fab")
		)
		(fp_line
			(start 0.67945 0.3048)
			(end 0.120396 0.3048)
			(stroke
				(width 0.1)
				(type default)
			)
			(layer "F.Fab")
		)
		(pad "1" smd circle
			(at -0.40005 0)
			(size 0 0)
			(layers "F.Cu" "F.Mask" "F.Paste")
			(net "P3V3_AUX")
		)
		(pad "2" smd circle
			(at 0.40005 0)
			(size 0 0)
			(layers "F.Cu" "F.Mask" "F.Paste")
			(net "GPU_BASE_STBY_EN")
		)
	)
	(footprint ""
		(layer "F.Cu")
		(at 407.627582 -416.899344 -90)
		(property "Reference" "C6590"
			(at 0 0 270)
			(layer "F.SilkS")
			(hide yes)
			(effects
				(font
					(size 1.27 1.27)
				)
			)
		)
		(property "Value" ""
			(at 0 0 270)
			(layer "F.Fab")
			(effects
				(font
					(size 1.27 1.27)
				)
			)
		)
		(duplicate_pad_numbers_are_jumpers no)
		(fp_line
			(start -0.299974 0.150114)
			(end -0.299974 -0.150114)
			(stroke
				(width 0.1)
				(type default)
			)
			(layer "F.Fab")
		)
		(fp_line
			(start 0.299974 0.150114)
			(end -0.299974 0.150114)
			(stroke
				(width 0.1)
				(type default)
			)
			(layer "F.Fab")
		)
		(fp_line
			(start -0.299974 -0.150114)
			(end 0.299974 -0.150114)
			(stroke
				(width 0.1)
				(type default)
			)
			(layer "F.Fab")
		)
		(fp_line
			(start 0.299974 -0.150114)
			(end 0.299974 0.150114)
			(stroke
				(width 0.1)
				(type default)
			)
			(layer "F.Fab")
		)
		(pad "1" smd rect
			(at -0.2667 0 270)
			(size 0.3048 0.381)
			(layers "F.Cu" "F.Mask" "F.Paste")
			(net "P5E_CPU0_P2_TX_BUF_C_DN<12>")
		)
		(pad "2" smd rect
			(at 0.2667 0 270)
			(size 0.3048 0.381)
			(layers "F.Cu" "F.Mask" "F.Paste")
			(net "P5E_CPU0_P2_TX_BUF_DN<12>")
		)
	)
)
